(kicad_pcb
	(version 20260206)
	(generator "pcbnew")
	(generator_version "10.0")
	(general
		(thickness 1.6)
		(legacy_teardrops no)
	)
	(paper "A4")
	(title_block
		(title "Bryce Canyon_IOM_IOC_16318-2_OCP.brd")
		(comment 1 "Bryce Canyon / footprints 361-366 of 1605")
	)
	(layers
		(0 "F.Cu" signal "TOP")
		(4 "In1.Cu" signal "L2GND")
		(6 "In2.Cu" signal "L3")
		(8 "In3.Cu" signal "L4VCC")
		(10 "In4.Cu" signal "L5VCC")
		(12 "In5.Cu" signal "L6")
		(14 "In6.Cu" signal "L7GND")
		(2 "B.Cu" signal "BOTTOM")
		(9 "F.Adhes" user "F.Adhesive")
		(11 "B.Adhes" user "B.Adhesive")
		(13 "F.Paste" user "Package Geometry/Pastemask Top")
		(15 "B.Paste" user "Package Geometry/Pastemask Bottom")
		(5 "F.SilkS" user "Ref Des/Silkscreen Top")
		(7 "B.SilkS" user "Ref Des/Silkscreen Bottom")
		(1 "F.Mask" user "Board Geometry/Soldermask Top")
		(3 "B.Mask" user "Board Geometry/Soldermask Bottom")
		(17 "Dwgs.User" user "User.Drawings")
		(19 "Cmts.User" user "User.Comments")
		(21 "Eco1.User" user "User.Eco1")
		(23 "Eco2.User" user "User.Eco2")
		(25 "Edge.Cuts" user "Board Geometry/Outline")
		(27 "Margin" user)
		(31 "F.CrtYd" user "Package Geometry/Place Bound Top")
		(29 "B.CrtYd" user "Package Geometry/Place Bound Bottom")
		(35 "F.Fab" user "Ref Des/Assembly Top")
		(33 "B.Fab" user "Ref Des/Assembly Bottom")
	)
	(footprint ""
		(layer "F.Cu")
		(at 176.6824 -60.1599 90)
		(property "Reference" "R579"
			(at 0 0 90)
			(layer "F.SilkS")
			(hide yes)
			(effects
				(font
					(size 1.27 1.27)
				)
			)
		)
		(property "Value" "2K2R2F-GP"
			(at 0.064008 -3.993896 90)
			(unlocked yes)
			(layer "F.Fab")
			(hide yes)
			(effects
				(font
					(size 1.016 1.016)
					(thickness 0.1524)
				)
			)
		)
		(property "Device Type" "R402H16"
			(at 0.064008 -5.517896 90)
			(unlocked yes)
			(layer "F.Fab")
			(hide yes)
			(effects
				(font
					(size 1.016 1.016)
					(thickness 0.1524)
				)
			)
		)
		(duplicate_pad_numbers_are_jumpers no)
		(fp_line
			(start 0.508 -0.9398)
			(end -0.508 -0.9398)
			(stroke
				(width 0.1524)
				(type default)
			)
			(layer "F.SilkS")
		)
		(fp_line
			(start -0.508 -0.9398)
			(end -0.508 0.9398)
			(stroke
				(width 0.1524)
				(type default)
			)
			(layer "F.SilkS")
		)
		(fp_rect
			(start -0.508 0.9398)
			(end 0.508 -0.9398)
			(stroke
				(width 0)
				(type default)
			)
			(fill no)
			(layer "F.CrtYd")
		)
		(fp_rect
			(start -0.508 0.9398)
			(end 0.508 -0.9398)
			(stroke
				(width 0)
				(type default)
			)
			(fill no)
			(layer "F.Fab")
		)
		(pad "1" smd custom
			(at 0 -0.4445 90)
			(size 0.1397 0.1397)
			(layers "F.Cu" "F.Mask" "F.Paste")
			(net "P1V8")
			(options
				(clearance outline)
				(anchor circle)
			)
			(primitives
				(gr_poly
					(pts
						(arc
							(start -0.1778 -0.2794)
							(mid -0.249642 -0.249642)
							(end -0.2794 -0.1778)
						)
						(arc
							(start -0.2794 0.1778)
							(mid -0.249642 0.249642)
							(end -0.1778 0.2794)
						)
						(arc
							(start 0.1778 0.2794)
							(mid 0.249642 0.249642)
							(end 0.2794 0.1778)
						)
						(arc
							(start 0.2794 -0.1778)
							(mid 0.249642 -0.249642)
							(end 0.1778 -0.2794)
						)
					)
					(width 0)
					(fill yes)
				)
			)
		)
		(pad "2" smd custom
			(at 0 0.4445 90)
			(size 0.1397 0.1397)
			(layers "F.Cu" "F.Mask" "F.Paste")
			(net "SBL_SDA")
			(options
				(clearance outline)
				(anchor circle)
			)
			(primitives
				(gr_poly
					(pts
						(arc
							(start -0.1778 -0.2794)
							(mid -0.249642 -0.249642)
							(end -0.2794 -0.1778)
						)
						(arc
							(start -0.2794 0.1778)
							(mid -0.249642 0.249642)
							(end -0.1778 0.2794)
						)
						(arc
							(start 0.1778 0.2794)
							(mid 0.249642 0.249642)
							(end 0.2794 0.1778)
						)
						(arc
							(start 0.2794 -0.1778)
							(mid 0.249642 -0.249642)
							(end 0.1778 -0.2794)
						)
					)
					(width 0)
					(fill yes)
				)
			)
		)
	)
	(footprint ""
		(layer "F.Cu")
		(at 93.09989 -54.526942)
		(property "Reference" "U36"
			(at 0 0 0)
			(layer "F.SilkS")
			(hide yes)
			(effects
				(font
					(size 1.27 1.27)
				)
			)
		)
		(property "Value" "SN74LVC1G08DCKR-GP"
			(at -2.3368 -8.6868 0)
			(unlocked yes)
			(layer "F.Fab")
			(hide yes)
			(effects
				(font
					(size 1.016 1.016)
					(thickness 0.1524)
				)
			)
		)
		(property "Device Type" "SC70-5H44"
			(at -2.3114 -10.414 0)
			(unlocked yes)
			(layer "F.Fab")
			(hide yes)
			(effects
				(font
					(size 1.016 1.016)
					(thickness 0.1524)
				)
			)
		)
		(duplicate_pad_numbers_are_jumpers no)
		(fp_line
			(start -1.27 -1.7018)
			(end 1.27 -1.7018)
			(stroke
				(width 0.1524)
				(type default)
			)
			(layer "F.SilkS")
		)
		(fp_line
			(start -1.27 1.7018)
			(end -1.27 -1.7018)
			(stroke
				(width 0.1524)
				(type default)
			)
			(layer "F.SilkS")
		)
		(fp_line
			(start 0.6604 -1.8034)
			(end 1.3843 -1.8034)
			(stroke
				(width 0.3302)
				(type default)
			)
			(layer "F.SilkS")
		)
		(fp_line
			(start 1.27 -1.7018)
			(end 1.27 1.7018)
			(stroke
				(width 0.1524)
				(type default)
			)
			(layer "F.SilkS")
		)
		(fp_line
			(start 1.27 1.7018)
			(end -1.27 1.7018)
			(stroke
				(width 0.1524)
				(type default)
			)
			(layer "F.SilkS")
		)
		(fp_line
			(start 1.3843 -1.8034)
			(end 1.3843 -1.1176)
			(stroke
				(width 0.3302)
				(type default)
			)
			(layer "F.SilkS")
		)
		(fp_rect
			(start -1.524 1.9558)
			(end 1.524 -1.9558)
			(stroke
				(width 0)
				(type default)
			)
			(fill no)
			(layer "F.CrtYd")
		)
		(fp_poly
			(pts
				(xy -1.524 -1.9558) (xy 1.524 -1.9558) (xy 1.524 1.9558) (xy -1.524 1.9558)
			)
			(stroke
				(width 0)
				(type default)
			)
			(fill no)
			(layer "F.Fab")
		)
		(pad "1" smd rect
			(at 0.65024 -0.8255)
			(size 0.4064 1.2192)
			(layers "F.Cu" "F.Mask" "F.Paste")
			(net "IOM_FULL_PWR_EN")
		)
		(pad "2" smd rect
			(at 0 -0.8255)
			(size 0.4064 1.2192)
			(layers "F.Cu" "F.Mask" "F.Paste")
			(net "IOM_STBY_PGOOD")
		)
		(pad "3" smd rect
			(at -0.65024 -0.8255)
			(size 0.4064 1.2192)
			(layers "F.Cu" "F.Mask" "F.Paste")
			(net "GND")
		)
		(pad "4" smd rect
			(at -0.65024 0.8255)
			(size 0.4064 1.2192)
			(layers "F.Cu" "F.Mask" "F.Paste")
			(net "P3V3_EN")
		)
		(pad "5" smd rect
			(at 0.65024 0.8255)
			(size 0.4064 1.2192)
			(layers "F.Cu" "F.Mask" "F.Paste")
			(net "P3V3_STBY")
		)
	)
	(footprint ""
		(layer "F.Cu")
		(at 185.693304 -152.051766)
		(property "Reference" "R473"
			(at 0 0 0)
			(layer "F.SilkS")
			(hide yes)
			(effects
				(font
					(size 1.27 1.27)
				)
			)
		)
		(property "Value" "10R3F-GP"
			(at -0.0254 -2.5146 0)
			(unlocked yes)
			(layer "F.Fab")
			(hide yes)
			(effects
				(font
					(size 1.016 1.016)
					(thickness 0.1524)
				)
			)
		)
		(property "Device Type" "R603H22"
			(at -0.0254 -4.0386 0)
			(unlocked yes)
			(layer "F.Fab")
			(hide yes)
			(effects
				(font
					(size 1.016 1.016)
					(thickness 0.1524)
				)
			)
		)
		(duplicate_pad_numbers_are_jumpers no)
		(fp_line
			(start -0.4826 0)
			(end -0.2032 0)
			(stroke
				(width 0.2032)
				(type default)
			)
			(layer "F.SilkS")
		)
		(fp_line
			(start 0.2032 0)
			(end 0.4826 0)
			(stroke
				(width 0.2032)
				(type default)
			)
			(layer "F.SilkS")
		)
		(fp_rect
			(start -0.5842 1.3335)
			(end 0.5842 -1.3335)
			(stroke
				(width 0)
				(type default)
			)
			(fill no)
			(layer "F.CrtYd")
		)
		(fp_rect
			(start -0.5842 1.3335)
			(end 0.5842 -1.3335)
			(stroke
				(width 0)
				(type default)
			)
			(fill no)
			(layer "F.Fab")
		)
		(pad "1" smd custom
			(at 0 -0.762)
			(size 0.2159 0.2159)
			(layers "F.Cu" "F.Mask" "F.Paste")
			(net "P5V_CC")
			(options
				(clearance outline)
				(anchor circle)
			)
			(primitives
				(gr_poly
					(pts
						(arc
							(start -0.3302 -0.4318)
							(mid -0.402042 -0.402042)
							(end -0.4318 -0.3302)
						)
						(arc
							(start -0.4318 0.3302)
							(mid -0.402042 0.402042)
							(end -0.3302 0.4318)
						)
						(arc
							(start 0.3302 0.4318)
							(mid 0.402042 0.402042)
							(end 0.4318 0.3302)
						)
						(arc
							(start 0.4318 -0.3302)
							(mid 0.402042 -0.402042)
							(end 0.3302 -0.4318)
						)
					)
					(width 0)
					(fill yes)
				)
			)
		)
		(pad "2" smd custom
			(at 0 0.762)
			(size 0.2159 0.2159)
			(layers "F.Cu" "F.Mask" "F.Paste")
			(net "P5V_VFB_R")
			(options
				(clearance outline)
				(anchor circle)
			)
			(primitives
				(gr_poly
					(pts
						(arc
							(start -0.3302 -0.4318)
							(mid -0.402042 -0.402042)
							(end -0.4318 -0.3302)
						)
						(arc
							(start -0.4318 0.3302)
							(mid -0.402042 0.402042)
							(end -0.3302 0.4318)
						)
						(arc
							(start 0.3302 0.4318)
							(mid 0.402042 0.402042)
							(end 0.4318 0.3302)
						)
						(arc
							(start 0.4318 -0.3302)
							(mid 0.402042 -0.402042)
							(end 0.3302 -0.4318)
						)
					)
					(width 0)
					(fill yes)
				)
			)
		)
	)
	(footprint ""
		(layer "F.Cu")
		(at 182.9562 -144.5514 90)
		(property "Reference" "R477"
			(at 0 0 90)
			(layer "F.SilkS")
			(hide yes)
			(effects
				(font
					(size 1.27 1.27)
				)
			)
		)
		(property "Value" "619KR2F-GP"
			(at 0.064008 -3.993896 90)
			(unlocked yes)
			(layer "F.Fab")
			(hide yes)
			(effects
				(font
					(size 1.016 1.016)
					(thickness 0.1524)
				)
			)
		)
		(property "Device Type" "R402H16"
			(at 0.064008 -5.517896 90)
			(unlocked yes)
			(layer "F.Fab")
			(hide yes)
			(effects
				(font
					(size 1.016 1.016)
					(thickness 0.1524)
				)
			)
		)
		(duplicate_pad_numbers_are_jumpers no)
		(fp_line
			(start 0.508 -0.9398)
			(end -0.508 -0.9398)
			(stroke
				(width 0.1524)
				(type default)
			)
			(layer "F.SilkS")
		)
		(fp_line
			(start -0.508 -0.9398)
			(end -0.508 0.9398)
			(stroke
				(width 0.1524)
				(type default)
			)
			(layer "F.SilkS")
		)
		(fp_rect
			(start -0.508 0.9398)
			(end 0.508 -0.9398)
			(stroke
				(width 0)
				(type default)
			)
			(fill no)
			(layer "F.CrtYd")
		)
		(fp_rect
			(start -0.508 0.9398)
			(end 0.508 -0.9398)
			(stroke
				(width 0)
				(type default)
			)
			(fill no)
			(layer "F.Fab")
		)
		(pad "1" smd custom
			(at 0 -0.4445 90)
			(size 0.1397 0.1397)
			(layers "F.Cu" "F.Mask" "F.Paste")
			(net "P5V_RF")
			(options
				(clearance outline)
				(anchor circle)
			)
			(primitives
				(gr_poly
					(pts
						(arc
							(start -0.1778 -0.2794)
							(mid -0.249642 -0.249642)
							(end -0.2794 -0.1778)
						)
						(arc
							(start -0.2794 0.1778)
							(mid -0.249642 0.249642)
							(end -0.1778 0.2794)
						)
						(arc
							(start 0.1778 0.2794)
							(mid 0.249642 0.249642)
							(end 0.2794 0.1778)
						)
						(arc
							(start 0.2794 -0.1778)
							(mid 0.249642 -0.249642)
							(end 0.1778 -0.2794)
						)
					)
					(width 0)
					(fill yes)
				)
			)
		)
		(pad "2" smd custom
			(at 0 0.4445 90)
			(size 0.1397 0.1397)
			(layers "F.Cu" "F.Mask" "F.Paste")
			(net "AGND_P5V")
			(options
				(clearance outline)
				(anchor circle)
			)
			(primitives
				(gr_poly
					(pts
						(arc
							(start -0.1778 -0.2794)
							(mid -0.249642 -0.249642)
							(end -0.2794 -0.1778)
						)
						(arc
							(start -0.2794 0.1778)
							(mid -0.249642 0.249642)
							(end -0.1778 0.2794)
						)
						(arc
							(start 0.1778 0.2794)
							(mid 0.249642 0.249642)
							(end 0.2794 0.1778)
						)
						(arc
							(start 0.2794 -0.1778)
							(mid 0.249642 -0.249642)
							(end 0.1778 -0.2794)
						)
					)
					(width 0)
					(fill yes)
				)
			)
		)
	)
	(footprint ""
		(layer "F.Cu")
		(at 122.99315 -14.9479 90)
		(property "Reference" "R432"
			(at 0 0 90)
			(layer "F.SilkS")
			(hide yes)
			(effects
				(font
					(size 1.27 1.27)
				)
			)
		)
		(property "Value" "100R2D-GP"
			(at 0.064008 -3.993896 90)
			(unlocked yes)
			(layer "F.Fab")
			(hide yes)
			(effects
				(font
					(size 1.016 1.016)
					(thickness 0.1524)
				)
			)
		)
		(property "Device Type" "R402H14"
			(at 0.064008 -5.517896 90)
			(unlocked yes)
			(layer "F.Fab")
			(hide yes)
			(effects
				(font
					(size 1.016 1.016)
					(thickness 0.1524)
				)
			)
		)
		(duplicate_pad_numbers_are_jumpers no)
		(fp_line
			(start 0.508 -0.9398)
			(end -0.508 -0.9398)
			(stroke
				(width 0.1524)
				(type default)
			)
			(layer "F.SilkS")
		)
		(fp_line
			(start -0.508 -0.9398)
			(end -0.508 0.9398)
			(stroke
				(width 0.1524)
				(type default)
			)
			(layer "F.SilkS")
		)
		(fp_rect
			(start -0.508 0.9398)
			(end 0.508 -0.9398)
			(stroke
				(width 0)
				(type default)
			)
			(fill no)
			(layer "F.CrtYd")
		)
		(fp_rect
			(start -0.508 0.9398)
			(end 0.508 -0.9398)
			(stroke
				(width 0)
				(type default)
			)
			(fill no)
			(layer "F.Fab")
		)
		(pad "1" smd custom
			(at 0 -0.4445 90)
			(size 0.1397 0.1397)
			(layers "F.Cu" "F.Mask" "F.Paste")
			(net "MB0_TEMP")
			(options
				(clearance outline)
				(anchor circle)
			)
			(primitives
				(gr_poly
					(pts
						(arc
							(start -0.1778 -0.2794)
							(mid -0.249642 -0.249642)
							(end -0.2794 -0.1778)
						)
						(arc
							(start -0.2794 0.1778)
							(mid -0.249642 0.249642)
							(end -0.1778 0.2794)
						)
						(arc
							(start 0.1778 0.2794)
							(mid 0.249642 0.249642)
							(end 0.2794 0.1778)
						)
						(arc
							(start 0.2794 -0.1778)
							(mid 0.249642 -0.249642)
							(end 0.1778 -0.2794)
						)
					)
					(width 0)
					(fill yes)
				)
			)
		)
		(pad "2" smd custom
			(at 0 0.4445 90)
			(size 0.1397 0.1397)
			(layers "F.Cu" "F.Mask" "F.Paste")
			(net "MB0_TEMP_C")
			(options
				(clearance outline)
				(anchor circle)
			)
			(primitives
				(gr_poly
					(pts
						(arc
							(start -0.1778 -0.2794)
							(mid -0.249642 -0.249642)
							(end -0.2794 -0.1778)
						)
						(arc
							(start -0.2794 0.1778)
							(mid -0.249642 0.249642)
							(end -0.1778 0.2794)
						)
						(arc
							(start 0.1778 0.2794)
							(mid 0.249642 0.249642)
							(end 0.2794 0.1778)
						)
						(arc
							(start 0.2794 -0.1778)
							(mid 0.249642 -0.249642)
							(end 0.1778 -0.2794)
						)
					)
					(width 0)
					(fill yes)
				)
			)
		)
	)
	(footprint ""
		(layer "F.Cu")
		(at 173.6598 -63.2714 90)
		(property "Reference" "R649"
			(at 0 0 90)
			(layer "F.SilkS")
			(hide yes)
			(effects
				(font
					(size 1.27 1.27)
				)
			)
		)
		(property "Value" "10KR2F-2-GP"
			(at 0.064008 -3.993896 90)
			(unlocked yes)
			(layer "F.Fab")
			(hide yes)
			(effects
				(font
					(size 1.016 1.016)
					(thickness 0.1524)
				)
			)
		)
		(property "Device Type" "R402H16"
			(at 0.064008 -5.517896 90)
			(unlocked yes)
			(layer "F.Fab")
			(hide yes)
			(effects
				(font
					(size 1.016 1.016)
					(thickness 0.1524)
				)
			)
		)
		(duplicate_pad_numbers_are_jumpers no)
		(fp_line
			(start 0.508 -0.9398)
			(end -0.508 -0.9398)
			(stroke
				(width 0.1524)
				(type default)
			)
			(layer "F.SilkS")
		)
		(fp_line
			(start -0.508 -0.9398)
			(end -0.508 0.9398)
			(stroke
				(width 0.1524)
				(type default)
			)
			(layer "F.SilkS")
		)
		(fp_rect
			(start -0.508 0.9398)
			(end 0.508 -0.9398)
			(stroke
				(width 0)
				(type default)
			)
			(fill no)
			(layer "F.CrtYd")
		)
		(fp_rect
			(start -0.508 0.9398)
			(end 0.508 -0.9398)
			(stroke
				(width 0)
				(type default)
			)
			(fill no)
			(layer "F.Fab")
		)
		(pad "1" smd custom
			(at 0 -0.4445 90)
			(size 0.1397 0.1397)
			(layers "F.Cu" "F.Mask" "F.Paste")
			(net "P1V8")
			(options
				(clearance outline)
				(anchor circle)
			)
			(primitives
				(gr_poly
					(pts
						(arc
							(start -0.1778 -0.2794)
							(mid -0.249642 -0.249642)
							(end -0.2794 -0.1778)
						)
						(arc
							(start -0.2794 0.1778)
							(mid -0.249642 0.249642)
							(end -0.1778 0.2794)
						)
						(arc
							(start 0.1778 0.2794)
							(mid 0.249642 0.249642)
							(end 0.2794 0.1778)
						)
						(arc
							(start 0.2794 -0.1778)
							(mid 0.249642 -0.249642)
							(end 0.1778 -0.2794)
						)
					)
					(width 0)
					(fill yes)
				)
			)
		)
		(pad "2" smd custom
			(at 0 0.4445 90)
			(size 0.1397 0.1397)
			(layers "F.Cu" "F.Mask" "F.Paste")
			(net "SYS_CORE_TRI#")
			(options
				(clearance outline)
				(anchor circle)
			)
			(primitives
				(gr_poly
					(pts
						(arc
							(start -0.1778 -0.2794)
							(mid -0.249642 -0.249642)
							(end -0.2794 -0.1778)
						)
						(arc
							(start -0.2794 0.1778)
							(mid -0.249642 0.249642)
							(end -0.1778 0.2794)
						)
						(arc
							(start 0.1778 0.2794)
							(mid 0.249642 0.249642)
							(end 0.2794 0.1778)
						)
						(arc
							(start 0.2794 -0.1778)
							(mid 0.249642 -0.249642)
							(end 0.1778 -0.2794)
						)
					)
					(width 0)
					(fill yes)
				)
			)
		)
	)
)
